# S9S_MB_2U (Grand Teton) — schematic netlist excerpt (pin names and nets, part order shuffled) for the footprints in the layout excerpt that follows; sources: Cadence DE-HDL packaged netlist, KiCad conversion of 03242023_DA0F0TMBIJ0_F0T_Motherboard_J_brd_V01_OCP.brd

R3833  Q_RES  100K 1% CHIP  pkg 0402LF  page 162 : A = P3V3_AUX ; B = P3V3_OCP_FAULT_2
C38  Q_CAP  2.2UF 6.3V 20% X6S  pkg C0402  page 94 : A = P3V3_AUX ; B = GND

(kicad_pcb
	(version 20260206)
	(generator "pcbnew")
	(generator_version "10.0")
	(general
		(thickness 1.6)
		(legacy_teardrops no)
	)
	(paper "A4")
	(title_block
		(title "03242023_DA0F0TMBIJ0_F0T_Motherboard_J_brd_V01_OCP.brd")
		(comment 1 "Grand Teton / footprints 4676-4677 of 6105")
	)
	(layers
		(0 "F.Cu" signal "TOP")
		(4 "In1.Cu" signal "GND")
		(6 "In2.Cu" signal "IN1")
		(8 "In3.Cu" signal "GND1")
		(10 "In4.Cu" signal "IN2")
		(12 "In5.Cu" signal "GND2")
		(14 "In6.Cu" signal "IN3")
		(16 "In7.Cu" signal "GND3")
		(18 "In8.Cu" signal "VCC")
		(20 "In9.Cu" signal "VCC1")
		(22 "In10.Cu" signal "GND4")
		(24 "In11.Cu" signal "IN4")
		(26 "In12.Cu" signal "GND5")
		(28 "In13.Cu" signal "IN5")
		(30 "In14.Cu" signal "GND6")
		(32 "In15.Cu" signal "IN6")
		(34 "In16.Cu" signal "GND7")
		(2 "B.Cu" signal "BOTTOM")
		(9 "F.Adhes" user "F.Adhesive")
		(11 "B.Adhes" user "B.Adhesive")
		(13 "F.Paste" user "Package Geometry/Pastemask Top")
		(15 "B.Paste" user "Package Geometry/Pastemask Bottom")
		(5 "F.SilkS" user "Ref Des/Silkscreen Top")
		(7 "B.SilkS" user "Ref Des/Silkscreen Bottom")
		(1 "F.Mask" user "Board Geometry/Soldermask Top")
		(3 "B.Mask" user "Board Geometry/Soldermask Bottom")
		(17 "Dwgs.User" user "User.Drawings")
		(19 "Cmts.User" user "User.Comments")
		(21 "Eco1.User" user "User.Eco1")
		(23 "Eco2.User" user "User.Eco2")
		(25 "Edge.Cuts" user "Board Geometry/Outline")
		(27 "Margin" user)
		(31 "F.CrtYd" user "Package Geometry/Place Bound Top")
		(29 "B.CrtYd" user "Package Geometry/Place Bound Bottom")
		(35 "F.Fab" user "Ref Des/Assembly Top")
		(33 "B.Fab" user "Ref Des/Assembly Bottom")
	)
	(footprint ""
		(layer "B.Cu")
		(at 444.485014 -319.263776 180)
		(property "Reference" "C38"
			(at 0 0 0)
			(layer "B.SilkS")
			(hide yes)
			(effects
				(font
					(size 1.27 1.27)
				)
				(justify mirror)
			)
		)
		(property "Value" ""
			(at 0 0 0)
			(layer "B.Fab")
			(effects
				(font
					(size 1.27 1.27)
				)
				(justify mirror)
			)
		)
		(duplicate_pad_numbers_are_jumpers no)
		(fp_line
			(start 0.7874 0.4064)
			(end 0.7874 -0.4064)
			(stroke
				(width 0.1524)
				(type default)
			)
			(layer "B.SilkS")
		)
		(fp_line
			(start 0.7874 -0.4064)
			(end -0.7874 -0.4064)
			(stroke
				(width 0.1524)
				(type default)
			)
			(layer "B.SilkS")
		)
		(fp_line
			(start -0.7874 0.4064)
			(end 0.7874 0.4064)
			(stroke
				(width 0.1524)
				(type default)
			)
			(layer "B.SilkS")
		)
		(fp_line
			(start -0.7874 -0.4064)
			(end -0.7874 0.4064)
			(stroke
				(width 0.1524)
				(type default)
			)
			(layer "B.SilkS")
		)
		(fp_line
			(start 0.67945 0.3048)
			(end 0.67945 -0.305054)
			(stroke
				(width 0.1)
				(type default)
			)
			(layer "B.Fab")
		)
		(fp_line
			(start 0.67945 -0.305054)
			(end 0.12065 -0.305054)
			(stroke
				(width 0.1)
				(type default)
			)
			(layer "B.Fab")
		)
		(fp_line
			(start 0.12065 0.3048)
			(end 0.67945 0.3048)
			(stroke
				(width 0.1)
				(type default)
			)
			(layer "B.Fab")
		)
		(fp_line
			(start 0.12065 0.2794)
			(end 0.12065 0.3048)
			(stroke
				(width 0.1)
				(type default)
			)
			(layer "B.Fab")
		)
		(fp_line
			(start 0.12065 -0.2794)
			(end -0.12065 -0.2794)
			(stroke
				(width 0.1)
				(type default)
			)
			(layer "B.Fab")
		)
		(fp_line
			(start 0.12065 -0.305054)
			(end 0.12065 -0.2794)
			(stroke
				(width 0.1)
				(type default)
			)
			(layer "B.Fab")
		)
		(fp_line
			(start -0.120396 0.3048)
			(end -0.120396 0.2794)
			(stroke
				(width 0.1)
				(type default)
			)
			(layer "B.Fab")
		)
		(fp_line
			(start -0.120396 0.2794)
			(end 0.12065 0.2794)
			(stroke
				(width 0.1)
				(type default)
			)
			(layer "B.Fab")
		)
		(fp_line
			(start -0.12065 -0.2794)
			(end -0.12065 -0.3048)
			(stroke
				(width 0.1)
				(type default)
			)
			(layer "B.Fab")
		)
		(fp_line
			(start -0.12065 -0.3048)
			(end -0.67945 -0.3048)
			(stroke
				(width 0.1)
				(type default)
			)
			(layer "B.Fab")
		)
		(fp_line
			(start -0.67945 0.3048)
			(end -0.120396 0.3048)
			(stroke
				(width 0.1)
				(type default)
			)
			(layer "B.Fab")
		)
		(fp_line
			(start -0.67945 -0.3048)
			(end -0.67945 0.3048)
			(stroke
				(width 0.1)
				(type default)
			)
			(layer "B.Fab")
		)
		(pad "1" smd circle
			(at 0.40005 0)
			(size 0 0)
			(layers "B.Cu" "B.Mask" "B.Paste")
			(net "P3V3_AUX")
		)
		(pad "2" smd circle
			(at -0.40005 0)
			(size 0 0)
			(layers "B.Cu" "B.Mask" "B.Paste")
			(net "GND")
		)
	)
	(footprint ""
		(layer "B.Cu")
		(at 83.62315 -52.082446 180)
		(property "Reference" "R3833"
			(at 0 0 0)
			(layer "B.SilkS")
			(hide yes)
			(effects
				(font
					(size 1.27 1.27)
				)
				(justify mirror)
			)
		)
		(property "Value" ""
			(at 0 0 0)
			(layer "B.Fab")
			(effects
				(font
					(size 1.27 1.27)
				)
				(justify mirror)
			)
		)
		(duplicate_pad_numbers_are_jumpers no)
		(fp_line
			(start 0.7874 0.4064)
			(end 0.7874 -0.4064)
			(stroke
				(width 0.1524)
				(type default)
			)
			(layer "B.SilkS")
		)
		(fp_line
			(start 0.7874 -0.4064)
			(end -0.7874 -0.4064)
			(stroke
				(width 0.1524)
				(type default)
			)
			(layer "B.SilkS")
		)
		(fp_line
			(start -0.7874 0.4064)
			(end 0.7874 0.4064)
			(stroke
				(width 0.1524)
				(type default)
			)
			(layer "B.SilkS")
		)
		(fp_line
			(start -0.7874 -0.4064)
			(end -0.7874 0.4064)
			(stroke
				(width 0.1524)
				(type default)
			)
			(layer "B.SilkS")
		)
		(fp_line
			(start 0.67945 0.3048)
			(end 0.67945 -0.305054)
			(stroke
				(width 0.1)
				(type default)
			)
			(layer "B.Fab")
		)
		(fp_line
			(start 0.67945 -0.305054)
			(end 0.12065 -0.305054)
			(stroke
				(width 0.1)
				(type default)
			)
			(layer "B.Fab")
		)
		(fp_line
			(start 0.12065 0.3048)
			(end 0.67945 0.3048)
			(stroke
				(width 0.1)
				(type default)
			)
			(layer "B.Fab")
		)
		(fp_line
			(start 0.12065 0.2794)
			(end 0.12065 0.3048)
			(stroke
				(width 0.1)
				(type default)
			)
			(layer "B.Fab")
		)
		(fp_line
			(start 0.12065 -0.2794)
			(end -0.12065 -0.2794)
			(stroke
				(width 0.1)
				(type default)
			)
			(layer "B.Fab")
		)
		(fp_line
			(start 0.12065 -0.305054)
			(end 0.12065 -0.2794)
			(stroke
				(width 0.1)
				(type default)
			)
			(layer "B.Fab")
		)
		(fp_line
			(start -0.120396 0.3048)
			(end -0.120396 0.2794)
			(stroke
				(width 0.1)
				(type default)
			)
			(layer "B.Fab")
		)
		(fp_line
			(start -0.120396 0.2794)
			(end 0.12065 0.2794)
			(stroke
				(width 0.1)
				(type default)
			)
			(layer "B.Fab")
		)
		(fp_line
			(start -0.12065 -0.2794)
			(end -0.12065 -0.3048)
			(stroke
				(width 0.1)
				(type default)
			)
			(layer "B.Fab")
		)
		(fp_line
			(start -0.12065 -0.3048)
			(end -0.67945 -0.3048)
			(stroke
				(width 0.1)
				(type default)
			)
			(layer "B.Fab")
		)
		(fp_line
			(start -0.67945 0.3048)
			(end -0.120396 0.3048)
			(stroke
				(width 0.1)
				(type default)
			)
			(layer "B.Fab")
		)
		(fp_line
			(start -0.67945 -0.3048)
			(end -0.67945 0.3048)
			(stroke
				(width 0.1)
				(type default)
			)
			(layer "B.Fab")
		)
		(pad "1" smd circle
			(at 0.40005 0)
			(size 0 0)
			(layers "B.Cu" "B.Mask" "B.Paste")
			(net "P3V3_AUX")
		)
		(pad "2" smd circle
			(at -0.40005 0)
			(size 0 0)
			(layers "B.Cu" "B.Mask" "B.Paste")
			(net "P3V3_OCP_FAULT_2")
		)
	)
)
